FILE_TYPE = CONNECTIVITY;
{Allegro Design Entry HDL 16.6-p007 (v16-6-112F) 10/10/2012}
"PAGE_NUMBER" = 207;
0"NC";
1"PVCCIN_CPU1\g";
2"GND\g";
3"GND\g";
4"GND\g";
5"VR_FET_SW_P12V_STBY_PVCCIN_CPU1\g";
6"GND\g";
7"VR_FET_SW_P12V_STBY_PVCCIN_CPU1\g";
8"GND\g";
9"P5V_STBY\g";
10"P5V_STBY\g";
11"GND\g";
12"PVCCIN_CPU1\g";
13"GND\g";
14"GND\g";
15"GND\g";
16"GND\g";
17"GND\g";
18"GND\g";
19"GND\g";
20"GND\g";
21"VR_PVCCIN_CPU1_PH2_VCIN";
22"ISENSE_PVCCIN_CPU1_PH2_IMON";
23"A_TSENSE_PVCCIN_CPU1";
24"VR_PVCCIN_CPU1_PH2_OCSET";
25"VR_PVCCIN_CPU1_PH1_OCSET";
26"VR_PVCCIN_CPU1_AIREF2";
27"VR_PVCCIN_CPU1_PH2_BOOT";
28"VR_PVCCIN_CPU1_PHASE1"VOLTAGE"5";
29"VR_PVCCIN_CPU1_PHASE1_RC";
30"VR_PVCCIN_CPU1_PHASE2_RC";
31"TP_PVCCINC_CPU1_PH1_GL_0";
32"A_TSENSE_PVCCIN_CPU1";
33"TP_PVCCINC_CPU1_PH1_GL_1";
34"VR_PVCCIN_CPU1_PH1_VCIN"VOLTAGE"5";
35"ISENSE_PVCCIN_CPU1_PH1_IMON";
36"VR_PVCCIN_CPU1_PH1_PHASE"VOLTAGE"5";
37"VR_PVCCIN_CPU1_PH1_BOOT";
38"VR_PVCCIN_CPU1_PWM1";
39"VR_PVCCIN_CPU1_AIREF1";
40"VR_PVCCIN_CPU1_PHASE2"VOLTAGE"5";
41"VR_PVCCIN_CPU1_PH2_BOOT_R";
42"VR_PVCCIN_CPU1_PWM2";
43"VR_PVCCIN_CPU1_PH2_PHASE"VOLTAGE"5";
44"TP_PVCCINC_CPU1_PH2_GL_0";
45"TP_PVCCINC_CPU1_PH2_GL_1";
46"VR_PVCCIN_CPU1_PH1_BOOT_R";
%"RES"
"1","(-4700,1025)","0","mstr_discrete","I100";
;
CDS_SEC"1"
CDS_LOCATION"RT17"
WATTAGE"1/10W"
MATERIAL"CHIP"
TOLERANCE"5.0%"
VALUE"0"
PART_NUMBER"G22178-002"
LOCATION"RT17"
PACK_TYPE"0603"
ROOM"NIC_SPRV"
BOM_COST"NT_GBE_BASE"
CDS_LIB"mstr_discrete"
SEC_TYPE"0603"
SEC"1";
"B"
$PN"2"41;
"A"
$PN"1"27;
%"RES"
"1","(-5300,2050)","0","mstr_discrete","I105";
;
LOCATION"R9R11"
PART_NUMBER"G21497-005"
PACK_TYPE"0402"
TOLERANCE"5%"
WATTAGE"1/16W"
VALUE"0.0"
MATERIAL"CHIP"
CDS_LOCATION"R9R11"
CDS_SEC"1"
ROOM"CPU0"
SEC"1"
SEC_TYPE"0402"
CDS_LIB"mstr_discrete"
BOM_COST"PROC_SIDEBAND";
"B"
$PN"2"10;
"A"
$PN"1"21;
%"RES"
"1","(-5400,4650)","0","mstr_discrete","I106";
;
WATTAGE"1/16W"
PACK_TYPE"0402"
MATERIAL"CHIP"
VALUE"0.0"
TOLERANCE"5%"
PART_NUMBER"G21497-005"
LOCATION"R9R2"
BOM_COST"PROC_SIDEBAND"
CDS_LIB"mstr_discrete"
SEC_TYPE"0402"
SEC"1"
ROOM"CPU0"
CDS_SEC"1"
CDS_LOCATION"R9R2";
"B"
$PN"2"9;
"A"
$PN"1"34;
%"IND-120NH-30-GP"
"1","(-1475,3575)","1","w_hdl","I107";
;
CDS_SEC"1"
CDS_LOCATION"L1E1"
TYPE"IRMS=66A@DELTA_T<40C"
VALUE"IND-120NH-30-GP"
RATED"ISAT=94A@25C"
PACK_SIZE"DCR=0.17MOHM"
ATTRIBUTE"120NH"
LOCATION"L1E1"
PART_NUMBER"068.1202N.M001"
CDS_LIB"w_hdl"
CDS_LMAN_SYM_OUTLINE"-75,100,75,-100"
SEC_TYPE"DISCRET-GB2"
SEC"1"
PACK_TYPE"DISCRET-GB2";
"F"
$PN"2"12;
"S"
$PN"1"28;
%"IND-120NH-30-GP"
"1","(-1425,975)","1","w_hdl","I108";
;
CDS_SEC"1"
CDS_LOCATION"L1D3"
PACK_SIZE"DCR=0.17MOHM"
ATTRIBUTE"120NH"
LOCATION"L1D3"
VALUE"IND-120NH-30-GP"
RATED"ISAT=94A@25C"
TYPE"IRMS=66A@DELTA_T<40C"
PART_NUMBER"068.1202N.M001"
CDS_LIB"w_hdl"
CDS_LMAN_SYM_OUTLINE"-75,100,75,-100"
SEC_TYPE"DISCRET-GB2"
SEC"1"
PACK_TYPE"DISCRET-GB2";
"F"
$PN"2"1;
"S"
$PN"1"40;
%"SC1U10V2KX-4-GP"
"1","(-5000,1575)","0","w_hdl","I109";
;
CDS_SEC"1"
CDS_LOCATION"C1E23"
LOCATION"C1E23"
VALUE"SC1U10V2KX-4-GP"
PACK_SIZE"0402"
RATED"10V"
TOLERANCE"10%"
ATTRIBUTE"1UF"
CDS_LMAN_SYM_OUTLINE"-50,25,50,-25"
CDS_LIB"w_hdl"
PART_NUMBER"78.10523.8FL"
SEC_TYPE"SMD-BCG6"
SEC"1"
PACK_TYPE"SMD-BCG6";
"2"
$PN"2"8;
"1"
$PN"1"10;
%"SC1U10V2KX-4-GP"
"1","(-5100,4125)","0","w_hdl","I110";
;
CDS_SEC"1"
CDS_LOCATION"C1E6"
TOLERANCE"10%"
ATTRIBUTE"1UF"
LOCATION"C1E6"
PACK_SIZE"0402"
RATED"10V"
VALUE"SC1U10V2KX-4-GP"
PACK_TYPE"SMD-BCG6"
SEC"1"
SEC_TYPE"SMD-BCG6"
PART_NUMBER"78.10523.8FL"
CDS_LIB"w_hdl"
CDS_LMAN_SYM_OUTLINE"-50,25,50,-25";
"2"
$PN"2"6;
"1"
$PN"1"9;
%"1R3F-GP"
"1","(-2225,3050)","0","w_hdl","I111";
;
CDS_SEC"1"
CDS_LOCATION"RT16"
LOCATION"RT16"
PACK_SIZE"0603"
RATED"1/10W"
ATTRIBUTE"1 OHM"
POP"NOPOP"
TOLERANCE"1%"
VALUE"1R3F-GP"
PACK_TYPE"RCL_GP"
SEC"1"
SEC_TYPE"RCL_GP"
PART_NUMBER"64.1R005.55L"
CDS_LIB"w_hdl"
CDS_LMAN_SYM_OUTLINE"-50,75,50,-75";
"2"
$PN"2"16;
"1"
$PN"1"29;
%"1R3F-GP"
"1","(-1925,550)","0","w_hdl","I112";
;
CDS_SEC"1"
CDS_LOCATION"RT18"
PACK_SIZE"0603"
VALUE"1R3F-GP"
ATTRIBUTE"1 OHM"
RATED"1/10W"
POP"NOPOP"
LOCATION"RT18"
TOLERANCE"1%"
CDS_LMAN_SYM_OUTLINE"-50,75,50,-75"
CDS_LIB"w_hdl"
PART_NUMBER"64.1R005.55L"
SEC_TYPE"RCL_GP"
SEC"1"
PACK_TYPE"RCL_GP";
"2"
$PN"2"19;
"1"
$PN"1"30;
%"IR354XX"
"1","(-3150,1250)","0","mstr_discrete","I113";
;
CDS_SEC"1"
MATERIAL"IC"
PART_NUMBER"H73688-001"
LOCATION"EU1D4"
VALUE"IR35411"
ROOM"PVCCIN_CPU1_PWR_VR"
CDS_LIB"mstr_discrete"
PACK_TYPE"SM"
SEC"1"
SEC_TYPE"SM"
CDS_LOCATION"EU1D4";
"TOUT_FLT"
$PN"36"23;
"NC"
$PN"31"0;
"OCSET"
$PN"37"24;
"IOUT"
$PN"38"22;
"SW"
$PN"10"40;
"BOOST"
$PN"33"41;
"REFIN"
$PN"39"26;
"PWM"
$PN"34"42;
"PHASE"
$PN"32"43;
"VIN<0>"
$PN"25"7;
"VCC"
$PN"3"21;
"VIN<1>"
$PN"30"7;
"EN"
$PN"35"10;
"VDRV"
$PN"4"10;
"VOS"
$PN"1"1;
"LGND"
$PN"2"4;
"PGND<1>"
$PN"7"4;
"PGND<2>"
$PN"40"4;
"PGND<0>"
$PN"5"4;
"GL<0>"
$PN"6"44;
"GL<1>"
$PN"41"45;
%"PVCCIN_CPU1"
"1","(-750,1050)","0","mstr_symbols","I14";
;
CDS_LIB"mstr_symbols"
VOLTAGE"2.0V"
BODY_TYPE"PLUMBING"
HDL_POWER"PVCCIN_CPU1";
"G\NAC"1;
%"GND"
"1","(-750,425)","0","mstr_symbols","I17";
;
VOLTAGE"0"
CDS_LIB"mstr_symbols"
SIZE"1B"
BOM_COST"PROC_VRD_VCCIN_CPU0"
ROOM"PVCCIN_CPU1_PWR_VR"
BODY_TYPE"PLUMBING"
HDL_POWER"GND";
"A\NAC"2;
%"CAP_A"
"1","(-1100,750)","0","dev_discrete","I18";
;
LOCATION"C1E3"
VALUE"22.0UF"
VOLTAGE"4V"
TOLERANCE"20%"
MATERIAL"X6S"
PACK_TYPE"0603V"
PART_NUMBER"E15431-004"
GROUP"PWR_MLCC_CAP"
CDS_LIB"dev_discrete"
CDS_LOCATION"C1E3"
BOM_COST"PROC_VRD_VCCIN_CPU0"
CDS_SEC"1"
SEC_TYPE"0603V"
SEC"1"
ROOM"PVCCIN_CPU1_PWR_VR";
"B"
$PN"2"2;
"A"
$PN"1"1;
%"GND"
"1","(-2400,3100)","0","mstr_symbols","I19";
;
CDS_LIB"mstr_symbols"
VOLTAGE"0"
SIZE"1B"
BOM_COST"PROC_VRD_VCCIN_CPU0"
ROOM"PVCCIN_CPU1_PWR_VR"
BODY_TYPE"PLUMBING"
HDL_POWER"GND";
"A\NAC"3;
%"IR354XX"
"1","(-3125,3850)","0","mstr_discrete","I20";
;
CDS_SEC"1"
LOCATION"EU1E2"
MATERIAL"IC"
PART_NUMBER"H73688-001"
SEC_TYPE"SM"
SEC"1"
CDS_LOCATION"EU1E2"
PACK_TYPE"SM"
CDS_LIB"mstr_discrete"
ROOM"PVCCIN_CPU1_PWR_VR"
VALUE"IR35411";
"TOUT_FLT"
$PN"36"32;
"NC"
$PN"31"0;
"OCSET"
$PN"37"25;
"IOUT"
$PN"38"35;
"SW"
$PN"10"28;
"BOOST"
$PN"33"46;
"REFIN"
$PN"39"39;
"PWM"
$PN"34"38;
"PHASE"
$PN"32"36;
"VIN<0>"
$PN"25"5;
"VCC"
$PN"3"34;
"VIN<1>"
$PN"30"5;
"EN"
$PN"35"9;
"VDRV"
$PN"4"9;
"VOS"
$PN"1"12;
"LGND"
$PN"2"3;
"PGND<1>"
$PN"7"3;
"PGND<2>"
$PN"40"3;
"PGND<0>"
$PN"5"3;
"GL<0>"
$PN"6"31;
"GL<1>"
$PN"41"33;
%"GND"
"1","(-2450,575)","0","mstr_symbols","I23";
;
CDS_LIB"mstr_symbols"
VOLTAGE"0"
SIZE"1B"
BOM_COST"PROC_VRD_VCCIN_CPU0"
ROOM"PVCCIN_CPU1_PWR_VR"
BODY_TYPE"PLUMBING"
HDL_POWER"GND";
"A\NAC"4;
%"VCC_CORE"
"1","(-6550,4525)","0","mstr_symbols","I27";
;
HDL_POWER"VR_FET_SW_P12V_STBY_PVCCIN_CPU1"
CDS_LIB"mstr_symbols";
"A"5;
%"CAP"
"1","(-4725,4150)","0","mstr_discrete","I28";
;
CDS_SEC"1"
LOCATION"C1E7"
VALUE"0.22UF"
VOLTAGE"16V"
TOLERANCE"10%"
PACK_TYPE"0402"
PART_NUMBER"A36096-155"
MATERIAL"X7R"
CDS_LIB"mstr_discrete"
ROOM"PVCCIN_CPU1_PWR_VR"
CDS_LOCATION"C1E7"
SEC"1"
SEC_TYPE"0402";
"A"
$PN"1"9;
"B"
$PN"2"6;
%"CAP"
"1","(-5675,3500)","2","mstr_discrete","I30";
;
CDS_SEC"1"
PART_NUMBER"A36096-104"
MATERIAL"X7R"
TOLERANCE"10%"
VOLTAGE"16V"
VALUE"0.220UF"
PACK_TYPE"0402"
LOCATION"C1E11"
SEC"1"
SPOF"TRUE"
SEC_TYPE"0402"
ROOM"PVCCIN_CPU1_PWR_VR"
NO_XNET_CONNECTION"1"
CDS_LOCATION"C1E11"
CDS_LIB"mstr_discrete";
"A"
$PN"1"37;
"B"
$PN"2"36;
%"CAP"
"1","(-5550,4100)","0","mstr_discrete","I32";
;
CDS_SEC"1"
MATERIAL"X6S"
PART_NUMBER"D97712-011"
PACK_TYPE"0402"
TOLERANCE"10%"
VOLTAGE"16V"
VALUE"1.0UF"
LOCATION"C1E8"
SEC"1"
SEC_TYPE"0402"
CDS_LOCATION"C1E8"
ROOM"PVCCIN_CPU1_PWR_VR"
CDS_LIB"mstr_discrete";
"A"
$PN"1"34;
"B"
$PN"2"6;
%"CAP_A"
"1","(-5850,4125)","0","dev_discrete","I33";
;
PACK_TYPE"0402V"
PART_NUMBER"A36096-030"
MATERIAL"X7R"
TOLERANCE"10%"
VOLTAGE"16V"
VALUE"0.1UF"
LOCATION"C1E14"
SEC"1"
SEC_TYPE"0402V"
CDS_SEC"1"
ROOM"PVCCIN_CPU1_PWR_VR"
CDS_LOCATION"C1E14"
CDS_LIB"dev_discrete";
"B"
$PN"2"6;
"A"
$PN"1"5;
%"CAP"
"1","(-6150,4125)","0","mstr_discrete","I34";
;
CDS_SEC"1"
PACK_TYPE"0402"
PART_NUMBER"D97712-011"
MATERIAL"X6S"
TOLERANCE"10%"
VOLTAGE"16V"
VALUE"1.0UF"
LOCATION"C1E13"
CDS_LIB"mstr_discrete"
ROOM"PVCCIN_CPU1_PWR_VR"
CDS_LOCATION"C1E13"
SEC"1"
SEC_TYPE"0402";
"A"
$PN"1"5;
"B"
$PN"2"6;
%"CAP"
"1","(-4600,1575)","0","mstr_discrete","I36";
;
CDS_SEC"1"
CDS_LOCATION"C1E25"
PART_NUMBER"A36096-155"
MATERIAL"X7R"
VOLTAGE"16V"
LOCATION"C1E25"
PACK_TYPE"0402"
TOLERANCE"10%"
VALUE"0.22UF"
SEC_TYPE"0402"
SEC"1"
CDS_LIB"mstr_discrete"
ROOM"PVCCIN_CPU1_PWR_VR";
"A"
$PN"1"10;
"B"
$PN"2"8;
%"CAP"
"1","(-5550,875)","2","mstr_discrete","I38";
;
CDS_SEC"1"
CDS_LOCATION"C1D36"
VOLTAGE"16V"
VALUE"0.220UF"
LOCATION"C1D36"
TOLERANCE"10%"
MATERIAL"X7R"
PART_NUMBER"A36096-104"
PACK_TYPE"0402"
CDS_LIB"mstr_discrete"
ROOM"PVCCIN_CPU1_PWR_VR"
NO_XNET_CONNECTION"1"
SEC"1"
SPOF"TRUE"
SEC_TYPE"0402";
"A"
$PN"1"27;
"B"
$PN"2"43;
%"CAP"
"1","(-5450,1525)","0","mstr_discrete","I40";
;
CDS_SEC"1"
CDS_LOCATION"C1E24"
TOLERANCE"10%"
LOCATION"C1E24"
VALUE"1.0UF"
VOLTAGE"16V"
MATERIAL"X6S"
PART_NUMBER"D97712-011"
PACK_TYPE"0402"
CDS_LIB"mstr_discrete"
ROOM"PVCCIN_CPU1_PWR_VR"
SEC_TYPE"0402"
SEC"1";
"A"
$PN"1"21;
"B"
$PN"2"8;
%"CAP_A"
"1","(-5725,1525)","0","dev_discrete","I41";
;
CDS_LOCATION"C1D34"
LOCATION"C1D34"
VALUE"0.1UF"
VOLTAGE"16V"
TOLERANCE"10%"
MATERIAL"X7R"
PART_NUMBER"A36096-030"
PACK_TYPE"0402V"
CDS_LIB"dev_discrete"
ROOM"PVCCIN_CPU1_PWR_VR"
CDS_SEC"1"
SEC"1"
SEC_TYPE"0402V";
"B"
$PN"2"8;
"A"
$PN"1"7;
%"CAP"
"1","(-6025,1550)","0","mstr_discrete","I42";
;
CDS_SEC"1"
CDS_LOCATION"C1D35"
LOCATION"C1D35"
VALUE"1.0UF"
VOLTAGE"16V"
TOLERANCE"10%"
MATERIAL"X6S"
PART_NUMBER"D97712-011"
PACK_TYPE"0402"
CDS_LIB"mstr_discrete"
SEC_TYPE"0402"
SEC"1"
ROOM"PVCCIN_CPU1_PWR_VR";
"A"
$PN"1"7;
"B"
$PN"2"8;
%"CAP"
"1","(-6425,4125)","0","mstr_discrete","I43";
;
CDS_SEC"1"
LOCATION"C9R7"
VALUE"10UF"
TOLERANCE"10%"
MATERIAL"X6S"
PART_NUMBER"C95333-007"
PACK_TYPE"0805"
VOLTAGE"16V"
CDS_LIB"mstr_discrete"
CDS_LOCATION"C9R7"
ROOM"PVCCIN_CPU1_PWR_VR"
SEC"1"
SEC_TYPE"0805";
"A"
$PN"1"5;
"B"
$PN"2"6;
%"CAP"
"1","(-6725,4125)","0","mstr_discrete","I44";
;
CDS_SEC"1"
MATERIAL"X6S"
TOLERANCE"10%"
VALUE"10UF"
LOCATION"C9R10"
VOLTAGE"16V"
PART_NUMBER"C95333-007"
PACK_TYPE"0805"
CDS_LIB"mstr_discrete"
ROOM"PVCCIN_CPU1_PWR_VR"
CDS_LOCATION"C9R10"
SEC"1"
SEC_TYPE"0805";
"A"
$PN"1"5;
"B"
$PN"2"6;
%"CAP"
"1","(-7025,4125)","0","mstr_discrete","I48";
;
CDS_SEC"1"
PACK_TYPE"0805"
MATERIAL"X6S"
TOLERANCE"10%"
VOLTAGE"16V"
VALUE"10UF"
PART_NUMBER"C95333-007"
LOCATION"C9R11"
CDS_LIB"mstr_discrete"
ROOM"PVCCIN_CPU1_PWR_VR"
CDS_LOCATION"C9R11"
SEC"1"
SEC_TYPE"0805";
"A"
$PN"1"5;
"B"
$PN"2"6;
%"GND"
"1","(-7025,3725)","0","mstr_symbols","I49";
;
ROOM"PVCCIN_CPU1_PWR_VR"
BOM_COST"PROC_VRD_VCCIN_CPU0"
SIZE"1B"
CDS_LIB"mstr_symbols"
VOLTAGE"0"
BODY_TYPE"PLUMBING"
HDL_POWER"GND";
"A\NAC"6;
%"CAP"
"1","(-6300,1550)","0","mstr_discrete","I50";
;
CDS_SEC"1"
LOCATION"C9P22"
VALUE"10UF"
VOLTAGE"16V"
TOLERANCE"10%"
MATERIAL"X6S"
PART_NUMBER"C95333-007"
PACK_TYPE"0805"
CDS_LIB"mstr_discrete"
ROOM"PVCCIN_CPU1_PWR_VR"
CDS_LOCATION"C9P22"
SEC"1"
SEC_TYPE"0805";
"A"
$PN"1"7;
"B"
$PN"2"8;
%"CAP"
"1","(-6575,1550)","0","mstr_discrete","I51";
;
CDS_SEC"1"
CDS_LOCATION"C9P25"
VALUE"10UF"
LOCATION"C9P25"
VOLTAGE"16V"
TOLERANCE"10%"
MATERIAL"X6S"
PART_NUMBER"C95333-007"
PACK_TYPE"0805"
CDS_LIB"mstr_discrete"
ROOM"PVCCIN_CPU1_PWR_VR"
SEC"1"
SEC_TYPE"0805";
"A"
$PN"1"7;
"B"
$PN"2"8;
%"VCC_CORE"
"1","(-6300,1900)","0","mstr_symbols","I53";
;
HDL_POWER"VR_FET_SW_P12V_STBY_PVCCIN_CPU1"
CDS_LIB"mstr_symbols";
"A"7;
%"CAP"
"1","(-6875,1550)","0","mstr_discrete","I54";
;
CDS_SEC"1"
CDS_LOCATION"C9P26"
LOCATION"C9P26"
VALUE"10UF"
VOLTAGE"16V"
TOLERANCE"10%"
MATERIAL"X6S"
PACK_TYPE"0805"
PART_NUMBER"C95333-007"
CDS_LIB"mstr_discrete"
SEC_TYPE"0805"
SEC"1"
ROOM"PVCCIN_CPU1_PWR_VR";
"A"
$PN"1"7;
"B"
$PN"2"8;
%"GND"
"1","(-6875,1150)","0","mstr_symbols","I55";
;
ROOM"PVCCIN_CPU1_PWR_VR"
BOM_COST"PROC_VRD_VCCIN_CPU0"
SIZE"1B"
VOLTAGE"0"
CDS_LIB"mstr_symbols"
BODY_TYPE"PLUMBING"
HDL_POWER"GND";
"A\NAC"8;
%"P5V_STBY"
"1","(-4225,4800)","0","mstr_symbols","I56";
;
CDS_LIB"mstr_symbols"
SIZE"1B"
VOLTAGE"5.0V"
BODY_TYPE"PLUMBING"
HDL_POWER"P5V_STBY";
"G\NAC"9;
%"P5V_STBY"
"1","(-4750,2200)","0","mstr_symbols","I57";
;
CDS_LIB"mstr_symbols"
VOLTAGE"5.0V"
SIZE"1B"
BODY_TYPE"PLUMBING"
HDL_POWER"P5V_STBY";
"G\NAC"10;
%"CAP_A"
"1","(-650,3350)","0","dev_discrete","I58";
;
VALUE"22.0UF"
VOLTAGE"4V"
TOLERANCE"20%"
LOCATION"C1E9"
PART_NUMBER"E15431-004"
PACK_TYPE"0603V"
MATERIAL"X6S"
GROUP"PWR_MLCC_CAP"
CDS_LIB"dev_discrete"
CDS_LOCATION"C1E9"
SEC"1"
CDS_SEC"1"
SEC_TYPE"0603V";
"B"
$PN"2"20;
"A"
$PN"1"12;
%"CAP_A"
"1","(-750,750)","0","dev_discrete","I59";
;
PACK_TYPE"0603V"
PART_NUMBER"E15431-004"
MATERIAL"X6S"
LOCATION"C9P3"
VOLTAGE"4V"
TOLERANCE"20%"
VALUE"22.0UF"
GROUP"PWR_MLCC_CAP"
CDS_SEC"1"
SEC_TYPE"0603V"
SEC"1"
CDS_LOCATION"C9P3"
CDS_LIB"dev_discrete";
"B"
$PN"2"2;
"A"
$PN"1"1;
%"RES"
"2","(-700,1425)","0","mstr_discrete","I67";
;
CDS_LOCATION"R1E13"
TOLERANCE"1%"
PART_NUMBER"G21796-187"
LOCATION"R1E13"
VALUE"68.1K"
WATTAGE"1/16W"
MATERIAL"EMPTY"
PACK_TYPE"0402"
CDS_SEC"1"
$SEC"1"
CDS_LIB"mstr_discrete";
"A"
$PN"1"24;
"B"
$PN"2"13;
%"RES"
"2","(-450,4050)","0","mstr_discrete","I68";
;
CDS_LOCATION"R1E14"
PART_NUMBER"G21796-187"
PACK_TYPE"0402"
MATERIAL"EMPTY"
WATTAGE"1/16W"
TOLERANCE"1%"
VALUE"68.1K"
LOCATION"R1E14"
CDS_SEC"1"
$SEC"1"
CDS_LIB"mstr_discrete";
"A"
$PN"1"25;
"B"
$PN"2"11;
%"GND"
"1","(-450,3850)","0","mstr_symbols","I69";
;
SIZE"1B"
VOLTAGE"0"
CDS_LIB"mstr_symbols"
BOM_COST"PROC_VRD_VCCIN_CPU0"
ROOM"PVCCIN_CPU1_PWR_VR"
BODY_TYPE"PLUMBING"
HDL_POWER"GND";
"A\NAC"11;
%"PVCCIN_CPU1"
"1","(-650,3650)","0","mstr_symbols","I7";
;
CDS_LIB"mstr_symbols"
VOLTAGE"2.0V"
BODY_TYPE"PLUMBING"
HDL_POWER"PVCCIN_CPU1";
"G\NAC"12;
%"GND"
"1","(-700,1200)","0","mstr_symbols","I70";
;
SIZE"1B"
VOLTAGE"0"
CDS_LIB"mstr_symbols"
BOM_COST"PROC_VRD_VCCIN_CPU0"
ROOM"PVCCIN_CPU1_PWR_VR"
BODY_TYPE"PLUMBING"
HDL_POWER"GND";
"A\NAC"13;
%"CAP_A"
"1","(-3850,3350)","0","dev_discrete","I71";
;
CDS_SEC"1"
CDS_LOCATION"CT24"
POP"NOPOP"
PART_NUMBER"A36096-030"
MATERIAL"X7R"
TOLERANCE"10%"
VALUE"0.1UF"
VOLTAGE"16V"
PACK_TYPE"0402V"
LOCATION"CT24"
CDS_LIB"dev_discrete"
ROOM"PVCCIN_CPU0_PWR_VR"
SEC"1"
SEC_TYPE"0402V";
"B"
$PN"2"14;
"A"
$PN"1"39;
%"GND"
"1","(-3850,3025)","0","mstr_symbols","I72";
;
CDS_LIB"mstr_symbols"
VOLTAGE"0"
SIZE"1B"
BOM_COST"PROC_VRD_VCCIN_CPU0"
ROOM"PVCCIN_CPU0_PWR_VR"
BODY_TYPE"PLUMBING"
HDL_POWER"GND";
"A\NAC"14;
%"CAP"
"1","(-2125,3850)","0","mstr_discrete","I74";
;
CDS_SEC"1"
CDS_LOCATION"CT22"
PACK_TYPE"0402LF"
PART_NUMBER"A36096-046"
MATERIAL"X7R"
TOLERANCE"10%"
VOLTAGE"50V"
VALUE"1000PF"
POP"NOPOP"
LOCATION"CT22"
CDS_LIB"mstr_discrete"
ROOM"VDDQ_KLM_PWR_VR"
SEC"1"
SEC_TYPE"0402LF";
"A"
$PN"1"32;
"B"
$PN"2"15;
%"GND"
"1","(-2125,3650)","0","mstr_symbols","I75";
;
CDS_LIB"mstr_symbols"
SIZE"1B"
VOLTAGE"0"
ROOM"VDDQ_KLM_PWR_VR"
BODY_TYPE"PLUMBING"
HDL_POWER"GND";
"A\NAC"15;
%"GND"
"1","(-2225,2850)","0","mstr_symbols","I78";
;
ROOM"PVCCIN_CPU0_PWR_VR"
BOM_COST"PROC_VRD_VCCIN_CPU0"
VOLTAGE"0"
SIZE"1B"
CDS_LIB"mstr_symbols"
BODY_TYPE"PLUMBING"
HDL_POWER"GND";
"A\NAC"16;
%"CAP_A"
"1","(-1100,3350)","0","dev_discrete","I8";
;
PART_NUMBER"E15431-004"
PACK_TYPE"0603V"
MATERIAL"X6S"
TOLERANCE"20%"
VOLTAGE"4V"
VALUE"22.0UF"
LOCATION"C9R8"
GROUP"PWR_MLCC_CAP"
ROOM"PVCCIN_CPU1_PWR_VR"
SEC"1"
SEC_TYPE"0603V"
CDS_SEC"1"
BOM_COST"PROC_VRD_VCCIN_CPU0"
CDS_LOCATION"C9R8"
CDS_LIB"dev_discrete";
"B"
$PN"2"20;
"A"
$PN"1"12;
%"GND"
"1","(-3825,500)","0","mstr_symbols","I80";
;
CDS_LIB"mstr_symbols"
VOLTAGE"0"
SIZE"1B"
BOM_COST"PROC_VRD_VCCIN_CPU0"
ROOM"PVCCIN_CPU0_PWR_VR"
BODY_TYPE"PLUMBING"
HDL_POWER"GND";
"A\NAC"17;
%"CAP_A"
"1","(-3825,750)","0","dev_discrete","I81";
;
CDS_SEC"1"
CDS_LOCATION"CT25"
VOLTAGE"16V"
TOLERANCE"10%"
PACK_TYPE"0402V"
POP"NOPOP"
MATERIAL"X7R"
LOCATION"CT25"
VALUE"0.1UF"
PART_NUMBER"A36096-030"
CDS_LIB"dev_discrete"
ROOM"PVCCIN_CPU0_PWR_VR"
SEC"1"
SEC_TYPE"0402V";
"B"
$PN"2"17;
"A"
$PN"1"26;
%"CAP"
"1","(-2075,1250)","0","mstr_discrete","I82";
;
CDS_SEC"1"
CDS_LOCATION"CT26"
VALUE"1000PF"
LOCATION"CT26"
VOLTAGE"50V"
TOLERANCE"10%"
MATERIAL"X7R"
PART_NUMBER"A36096-046"
PACK_TYPE"0402LF"
POP"NOPOP"
CDS_LIB"mstr_discrete"
ROOM"VDDQ_KLM_PWR_VR"
SEC"1"
SEC_TYPE"0402LF";
"A"
$PN"1"23;
"B"
$PN"2"18;
%"GND"
"1","(-2075,1050)","0","mstr_symbols","I83";
;
CDS_LIB"mstr_symbols"
ROOM"VDDQ_KLM_PWR_VR"
VOLTAGE"0"
SIZE"1B"
BODY_TYPE"PLUMBING"
HDL_POWER"GND";
"A\NAC"18;
%"GND"
"1","(-1925,350)","0","mstr_symbols","I86";
;
CDS_LIB"mstr_symbols"
SIZE"1B"
VOLTAGE"0"
BOM_COST"PROC_VRD_VCCIN_CPU0"
ROOM"PVCCIN_CPU0_PWR_VR"
BODY_TYPE"PLUMBING"
HDL_POWER"GND";
"A\NAC"19;
%"GND"
"1","(-650,3000)","0","mstr_symbols","I9";
;
VOLTAGE"0"
CDS_LIB"mstr_symbols"
BOM_COST"PROC_VRD_VCCIN_CPU0"
ROOM"PVCCIN_CPU1_PWR_VR"
SIZE"1B"
BODY_TYPE"PLUMBING"
HDL_POWER"GND";
"A\NAC"20;
%"CAP"
"1","(-2225,3400)","0","mstr_discrete","I95";
;
CDS_SEC"1"
CDS_LOCATION"CT23"
PART_NUMBER"A36096-046"
POP"NOPOP"
MATERIAL"X7R"
TOLERANCE"10%"
VOLTAGE"50V"
PACK_TYPE"0402LF"
VALUE"1000PF"
LOCATION"CT23"
CDS_LIB"mstr_discrete"
ROOM"VDDQ_KLM_PWR_VR"
SEC"1"
SEC_TYPE"0402LF";
"A"
$PN"1"28;
"B"
$PN"2"29;
%"CAP"
"1","(-1925,825)","0","mstr_discrete","I96";
;
CDS_SEC"1"
CDS_LOCATION"CT27"
PART_NUMBER"A36096-046"
POP"NOPOP"
LOCATION"CT27"
VALUE"1000PF"
MATERIAL"X7R"
PACK_TYPE"0402LF"
VOLTAGE"50V"
TOLERANCE"10%"
ROOM"VDDQ_KLM_PWR_VR"
CDS_LIB"mstr_discrete"
SEC"1"
SEC_TYPE"0402LF";
"A"
$PN"1"40;
"B"
$PN"2"30;
%"RES"
"1","(-4825,3675)","0","mstr_discrete","I99";
;
CDS_SEC"1"
CDS_LOCATION"RT15"
TOLERANCE"5.0%"
PACK_TYPE"0603"
WATTAGE"1/10W"
MATERIAL"CHIP"
PART_NUMBER"G22178-002"
LOCATION"RT15"
VALUE"0"
CDS_LIB"mstr_discrete"
BOM_COST"NT_GBE_BASE"
ROOM"NIC_SPRV"
SEC"1"
SEC_TYPE"0603";
"B"
$PN"2"46;
"A"
$PN"1"37;
END.
